# S9S_MB_2U (Grand Teton) — schematic netlist excerpt (pin names and nets, part order shuffled) for the footprints in the layout excerpt that follows; sources: Cadence DE-HDL packaged netlist, KiCad conversion of 03242023_DA0F0TMBIJ0_F0T_Motherboard_J_brd_V01_OCP.brd

R3975  Q_RES  0 5% EMPTY  pkg 0402LF  page 192 : A = P12V_E1S_SENSE_0 ; B = P12V_E1S_0_ISENSE_MAM_TIC
C1292  Q_CAP  0.1UF 25V 10% X7R  pkg 0402  page 134 : A = P3V3_AUX ; B = GND

(kicad_pcb
	(version 20260206)
	(generator "pcbnew")
	(generator_version "10.0")
	(general
		(thickness 1.6)
		(legacy_teardrops no)
	)
	(paper "A4")
	(title_block
		(title "03242023_DA0F0TMBIJ0_F0T_Motherboard_J_brd_V01_OCP.brd")
		(comment 1 "Grand Teton / footprints 3177-3178 of 6105")
	)
	(layers
		(0 "F.Cu" signal "TOP")
		(4 "In1.Cu" signal "GND")
		(6 "In2.Cu" signal "IN1")
		(8 "In3.Cu" signal "GND1")
		(10 "In4.Cu" signal "IN2")
		(12 "In5.Cu" signal "GND2")
		(14 "In6.Cu" signal "IN3")
		(16 "In7.Cu" signal "GND3")
		(18 "In8.Cu" signal "VCC")
		(20 "In9.Cu" signal "VCC1")
		(22 "In10.Cu" signal "GND4")
		(24 "In11.Cu" signal "IN4")
		(26 "In12.Cu" signal "GND5")
		(28 "In13.Cu" signal "IN5")
		(30 "In14.Cu" signal "GND6")
		(32 "In15.Cu" signal "IN6")
		(34 "In16.Cu" signal "GND7")
		(2 "B.Cu" signal "BOTTOM")
		(9 "F.Adhes" user "F.Adhesive")
		(11 "B.Adhes" user "B.Adhesive")
		(13 "F.Paste" user "Package Geometry/Pastemask Top")
		(15 "B.Paste" user "Package Geometry/Pastemask Bottom")
		(5 "F.SilkS" user "Ref Des/Silkscreen Top")
		(7 "B.SilkS" user "Ref Des/Silkscreen Bottom")
		(1 "F.Mask" user "Board Geometry/Soldermask Top")
		(3 "B.Mask" user "Board Geometry/Soldermask Bottom")
		(17 "Dwgs.User" user "User.Drawings")
		(19 "Cmts.User" user "User.Comments")
		(21 "Eco1.User" user "User.Eco1")
		(23 "Eco2.User" user "User.Eco2")
		(25 "Edge.Cuts" user "Board Geometry/Outline")
		(27 "Margin" user)
		(31 "F.CrtYd" user "Package Geometry/Place Bound Top")
		(29 "B.CrtYd" user "Package Geometry/Place Bound Bottom")
		(35 "F.Fab" user "Ref Des/Assembly Top")
		(33 "B.Fab" user "Ref Des/Assembly Bottom")
	)
	(footprint ""
		(layer "F.Cu")
		(at 258.25958 -57.911492 90)
		(property "Reference" "R3975"
			(at 0 0 90)
			(layer "F.SilkS")
			(hide yes)
			(effects
				(font
					(size 1.27 1.27)
				)
			)
		)
		(property "Value" ""
			(at 0 0 90)
			(layer "F.Fab")
			(effects
				(font
					(size 1.27 1.27)
				)
			)
		)
		(duplicate_pad_numbers_are_jumpers no)
		(fp_line
			(start 0.7874 -0.4064)
			(end 0.7874 0.4064)
			(stroke
				(width 0.1524)
				(type default)
			)
			(layer "F.SilkS")
		)
		(fp_line
			(start -0.7874 -0.4064)
			(end 0.7874 -0.4064)
			(stroke
				(width 0.1524)
				(type default)
			)
			(layer "F.SilkS")
		)
		(fp_line
			(start 0.7874 0.4064)
			(end -0.7874 0.4064)
			(stroke
				(width 0.1524)
				(type default)
			)
			(layer "F.SilkS")
		)
		(fp_line
			(start -0.7874 0.4064)
			(end -0.7874 -0.4064)
			(stroke
				(width 0.1524)
				(type default)
			)
			(layer "F.SilkS")
		)
		(fp_line
			(start -0.12065 -0.305054)
			(end -0.12065 -0.2794)
			(stroke
				(width 0.1)
				(type default)
			)
			(layer "F.Fab")
		)
		(fp_line
			(start -0.67945 -0.305054)
			(end -0.12065 -0.305054)
			(stroke
				(width 0.1)
				(type default)
			)
			(layer "F.Fab")
		)
		(fp_line
			(start 0.67945 -0.3048)
			(end 0.67945 0.3048)
			(stroke
				(width 0.1)
				(type default)
			)
			(layer "F.Fab")
		)
		(fp_line
			(start 0.12065 -0.3048)
			(end 0.67945 -0.3048)
			(stroke
				(width 0.1)
				(type default)
			)
			(layer "F.Fab")
		)
		(fp_line
			(start 0.12065 -0.2794)
			(end 0.12065 -0.3048)
			(stroke
				(width 0.1)
				(type default)
			)
			(layer "F.Fab")
		)
		(fp_line
			(start -0.12065 -0.2794)
			(end 0.12065 -0.2794)
			(stroke
				(width 0.1)
				(type default)
			)
			(layer "F.Fab")
		)
		(fp_line
			(start 0.120396 0.2794)
			(end -0.12065 0.2794)
			(stroke
				(width 0.1)
				(type default)
			)
			(layer "F.Fab")
		)
		(fp_line
			(start -0.12065 0.2794)
			(end -0.12065 0.3048)
			(stroke
				(width 0.1)
				(type default)
			)
			(layer "F.Fab")
		)
		(fp_line
			(start 0.67945 0.3048)
			(end 0.120396 0.3048)
			(stroke
				(width 0.1)
				(type default)
			)
			(layer "F.Fab")
		)
		(fp_line
			(start 0.120396 0.3048)
			(end 0.120396 0.2794)
			(stroke
				(width 0.1)
				(type default)
			)
			(layer "F.Fab")
		)
		(fp_line
			(start -0.12065 0.3048)
			(end -0.67945 0.3048)
			(stroke
				(width 0.1)
				(type default)
			)
			(layer "F.Fab")
		)
		(fp_line
			(start -0.67945 0.3048)
			(end -0.67945 -0.305054)
			(stroke
				(width 0.1)
				(type default)
			)
			(layer "F.Fab")
		)
		(pad "1" smd rect
			(at -0.40005 0 270)
			(size 0.4572 0.508)
			(layers "F.Cu" "F.Mask" "F.Paste")
			(net "P12V_E1S_SENSE_0")
		)
		(pad "2" smd rect
			(at 0.40005 0 270)
			(size 0.4572 0.508)
			(layers "F.Cu" "F.Mask" "F.Paste")
			(net "P12V_E1S_0_ISENSE_MAM_TIC")
		)
	)
	(footprint ""
		(layer "F.Cu")
		(at 107.87888 -57.241948)
		(property "Reference" "C1292"
			(at 0 0 0)
			(layer "F.SilkS")
			(hide yes)
			(effects
				(font
					(size 1.27 1.27)
				)
			)
		)
		(property "Value" ""
			(at 0 0 0)
			(layer "F.Fab")
			(effects
				(font
					(size 1.27 1.27)
				)
			)
		)
		(duplicate_pad_numbers_are_jumpers no)
		(fp_line
			(start -0.7874 -0.4064)
			(end 0.7874 -0.4064)
			(stroke
				(width 0.1524)
				(type default)
			)
			(layer "F.SilkS")
		)
		(fp_line
			(start -0.7874 0.4064)
			(end -0.7874 -0.4064)
			(stroke
				(width 0.1524)
				(type default)
			)
			(layer "F.SilkS")
		)
		(fp_line
			(start 0.7874 -0.4064)
			(end 0.7874 0.4064)
			(stroke
				(width 0.1524)
				(type default)
			)
			(layer "F.SilkS")
		)
		(fp_line
			(start 0.7874 0.4064)
			(end -0.7874 0.4064)
			(stroke
				(width 0.1524)
				(type default)
			)
			(layer "F.SilkS")
		)
		(fp_line
			(start -0.67945 -0.305054)
			(end -0.12065 -0.305054)
			(stroke
				(width 0.1)
				(type default)
			)
			(layer "F.Fab")
		)
		(fp_line
			(start -0.67945 0.3048)
			(end -0.67945 -0.305054)
			(stroke
				(width 0.1)
				(type default)
			)
			(layer "F.Fab")
		)
		(fp_line
			(start -0.12065 -0.305054)
			(end -0.12065 -0.2794)
			(stroke
				(width 0.1)
				(type default)
			)
			(layer "F.Fab")
		)
		(fp_line
			(start -0.12065 -0.2794)
			(end 0.12065 -0.2794)
			(stroke
				(width 0.1)
				(type default)
			)
			(layer "F.Fab")
		)
		(fp_line
			(start -0.12065 0.2794)
			(end -0.12065 0.3048)
			(stroke
				(width 0.1)
				(type default)
			)
			(layer "F.Fab")
		)
		(fp_line
			(start -0.12065 0.3048)
			(end -0.67945 0.3048)
			(stroke
				(width 0.1)
				(type default)
			)
			(layer "F.Fab")
		)
		(fp_line
			(start 0.120396 0.2794)
			(end -0.12065 0.2794)
			(stroke
				(width 0.1)
				(type default)
			)
			(layer "F.Fab")
		)
		(fp_line
			(start 0.120396 0.3048)
			(end 0.120396 0.2794)
			(stroke
				(width 0.1)
				(type default)
			)
			(layer "F.Fab")
		)
		(fp_line
			(start 0.12065 -0.3048)
			(end 0.67945 -0.3048)
			(stroke
				(width 0.1)
				(type default)
			)
			(layer "F.Fab")
		)
		(fp_line
			(start 0.12065 -0.2794)
			(end 0.12065 -0.3048)
			(stroke
				(width 0.1)
				(type default)
			)
			(layer "F.Fab")
		)
		(fp_line
			(start 0.67945 -0.3048)
			(end 0.67945 0.3048)
			(stroke
				(width 0.1)
				(type default)
			)
			(layer "F.Fab")
		)
		(fp_line
			(start 0.67945 0.3048)
			(end 0.120396 0.3048)
			(stroke
				(width 0.1)
				(type default)
			)
			(layer "F.Fab")
		)
		(pad "1" smd circle
			(at -0.40005 0)
			(size 0 0)
			(layers "F.Cu" "F.Mask" "F.Paste")
			(net "P3V3_AUX")
		)
		(pad "2" smd circle
			(at 0.40005 0)
			(size 0 0)
			(layers "F.Cu" "F.Mask" "F.Paste")
			(net "GND")
		)
	)
)
